(kicad_pcb
	(version 20260206)
	(generator "pcbnew")
	(generator_version "10.0")
	(general
		(thickness 1.6)
		(legacy_teardrops no)
	)
	(paper "A4")
	(title_block
		(title "03242023_DA0F0TMBIJ0_F0T_Motherboard_J_brd_V01_OCP.brd")
		(comment 1 "Grand Teton / footprints 4803-4809 of 6105")
	)
	(layers
		(0 "F.Cu" signal "TOP")
		(4 "In1.Cu" signal "GND")
		(6 "In2.Cu" signal "IN1")
		(8 "In3.Cu" signal "GND1")
		(10 "In4.Cu" signal "IN2")
		(12 "In5.Cu" signal "GND2")
		(14 "In6.Cu" signal "IN3")
		(16 "In7.Cu" signal "GND3")
		(18 "In8.Cu" signal "VCC")
		(20 "In9.Cu" signal "VCC1")
		(22 "In10.Cu" signal "GND4")
		(24 "In11.Cu" signal "IN4")
		(26 "In12.Cu" signal "GND5")
		(28 "In13.Cu" signal "IN5")
		(30 "In14.Cu" signal "GND6")
		(32 "In15.Cu" signal "IN6")
		(34 "In16.Cu" signal "GND7")
		(2 "B.Cu" signal "BOTTOM")
		(9 "F.Adhes" user "F.Adhesive")
		(11 "B.Adhes" user "B.Adhesive")
		(13 "F.Paste" user "Package Geometry/Pastemask Top")
		(15 "B.Paste" user "Package Geometry/Pastemask Bottom")
		(5 "F.SilkS" user "Ref Des/Silkscreen Top")
		(7 "B.SilkS" user "Ref Des/Silkscreen Bottom")
		(1 "F.Mask" user "Board Geometry/Soldermask Top")
		(3 "B.Mask" user "Board Geometry/Soldermask Bottom")
		(17 "Dwgs.User" user "User.Drawings")
		(19 "Cmts.User" user "User.Comments")
		(21 "Eco1.User" user "User.Eco1")
		(23 "Eco2.User" user "User.Eco2")
		(25 "Edge.Cuts" user "Board Geometry/Outline")
		(27 "Margin" user)
		(31 "F.CrtYd" user "Package Geometry/Place Bound Top")
		(29 "B.CrtYd" user "Package Geometry/Place Bound Bottom")
		(35 "F.Fab" user "Ref Des/Assembly Top")
		(33 "B.Fab" user "Ref Des/Assembly Bottom")
	)
	(footprint ""
		(layer "B.Cu")
		(at 170.824398 -193.02603 90)
		(property "Reference" "R153"
			(at 0 0 90)
			(layer "B.SilkS")
			(hide yes)
			(effects
				(font
					(size 1.27 1.27)
				)
				(justify mirror)
			)
		)
		(property "Value" ""
			(at 0 0 90)
			(layer "B.Fab")
			(effects
				(font
					(size 1.27 1.27)
				)
				(justify mirror)
			)
		)
		(duplicate_pad_numbers_are_jumpers no)
		(fp_line
			(start 0.7874 -0.4064)
			(end -0.7874 -0.4064)
			(stroke
				(width 0.1524)
				(type default)
			)
			(layer "B.SilkS")
		)
		(fp_line
			(start -0.7874 -0.4064)
			(end -0.7874 0.4064)
			(stroke
				(width 0.1524)
				(type default)
			)
			(layer "B.SilkS")
		)
		(fp_line
			(start 0.7874 0.4064)
			(end 0.7874 -0.4064)
			(stroke
				(width 0.1524)
				(type default)
			)
			(layer "B.SilkS")
		)
		(fp_line
			(start -0.7874 0.4064)
			(end 0.7874 0.4064)
			(stroke
				(width 0.1524)
				(type default)
			)
			(layer "B.SilkS")
		)
		(fp_line
			(start 0.67945 -0.305054)
			(end 0.12065 -0.305054)
			(stroke
				(width 0.1)
				(type default)
			)
			(layer "B.Fab")
		)
		(fp_line
			(start 0.12065 -0.305054)
			(end 0.12065 -0.2794)
			(stroke
				(width 0.1)
				(type default)
			)
			(layer "B.Fab")
		)
		(fp_line
			(start -0.12065 -0.3048)
			(end -0.67945 -0.3048)
			(stroke
				(width 0.1)
				(type default)
			)
			(layer "B.Fab")
		)
		(fp_line
			(start -0.67945 -0.3048)
			(end -0.67945 0.3048)
			(stroke
				(width 0.1)
				(type default)
			)
			(layer "B.Fab")
		)
		(fp_line
			(start 0.12065 -0.2794)
			(end -0.12065 -0.2794)
			(stroke
				(width 0.1)
				(type default)
			)
			(layer "B.Fab")
		)
		(fp_line
			(start -0.12065 -0.2794)
			(end -0.12065 -0.3048)
			(stroke
				(width 0.1)
				(type default)
			)
			(layer "B.Fab")
		)
		(fp_line
			(start 0.12065 0.2794)
			(end 0.12065 0.3048)
			(stroke
				(width 0.1)
				(type default)
			)
			(layer "B.Fab")
		)
		(fp_line
			(start -0.120396 0.2794)
			(end 0.12065 0.2794)
			(stroke
				(width 0.1)
				(type default)
			)
			(layer "B.Fab")
		)
		(fp_line
			(start 0.67945 0.3048)
			(end 0.67945 -0.305054)
			(stroke
				(width 0.1)
				(type default)
			)
			(layer "B.Fab")
		)
		(fp_line
			(start 0.12065 0.3048)
			(end 0.67945 0.3048)
			(stroke
				(width 0.1)
				(type default)
			)
			(layer "B.Fab")
		)
		(fp_line
			(start -0.120396 0.3048)
			(end -0.120396 0.2794)
			(stroke
				(width 0.1)
				(type default)
			)
			(layer "B.Fab")
		)
		(fp_line
			(start -0.67945 0.3048)
			(end -0.120396 0.3048)
			(stroke
				(width 0.1)
				(type default)
			)
			(layer "B.Fab")
		)
		(pad "1" smd circle
			(at 0.40005 0 270)
			(size 0 0)
			(layers "B.Cu" "B.Mask" "B.Paste")
			(net "PWRGD_DRAMPWRGD_CPU1_GH_LVC1_R2")
		)
		(pad "2" smd circle
			(at -0.40005 0 270)
			(size 0 0)
			(layers "B.Cu" "B.Mask" "B.Paste")
			(net "PVCCD_HV_CPU1")
		)
	)
	(footprint ""
		(layer "B.Cu")
		(at 325.688706 -73.499472 180)
		(property "Reference" "PJ62"
			(at -4.991354 -1.577594 0)
			(unlocked yes)
			(layer "B.SilkS")
			(effects
				(font
					(size 0.7874 0.5842)
					(thickness 0.1524)
				)
				(justify left mirror)
			)
		)
		(property "Value" ""
			(at 0 0 0)
			(layer "B.Fab")
			(effects
				(font
					(size 1.27 1.27)
				)
				(justify mirror)
			)
		)
		(duplicate_pad_numbers_are_jumpers no)
		(pad "1" smd circle
			(at 0.7493 0 270)
			(size 0 0)
			(layers "B.Cu" "B.Mask" "B.Paste")
			(net "SH_P1V05_PCH_AUX_P")
		)
		(pad "2" smd rect
			(at -0.7493 0 90)
			(size 0.7112 0.8128)
			(layers "B.Cu" "B.Mask" "B.Paste")
			(net "P1V05_PCH_AUX")
		)
		(zone
			(layer "B.Cu")
			(hatch none 0.5)
			(connect_pads
				(clearance 0)
			)
			(min_thickness 0.25)
			(keepout
				(tracks allowed)
				(vias not_allowed)
				(pads allowed)
				(copperpour not_allowed)
				(footprints allowed)
			)
			(placement
				(enabled no)
				(sheetname "")
			)
			(fill
				(thermal_gap 0.5)
				(thermal_bridge_width 0.5)
				(island_removal_mode 0)
			)
			(polygon
				(pts
					(xy 324.507606 -73.910952) (xy 324.507606 -73.093326) (xy 326.895206 -73.093326) (xy 326.895206 -73.910952)
				)
			)
		)
	)
	(footprint ""
		(layer "B.Cu")
		(at 410.830014 -321.549776 -90)
		(property "Reference" "C30"
			(at 0 0 90)
			(layer "B.SilkS")
			(hide yes)
			(effects
				(font
					(size 1.27 1.27)
				)
				(justify mirror)
			)
		)
		(property "Value" ""
			(at 0 0 90)
			(layer "B.Fab")
			(effects
				(font
					(size 1.27 1.27)
				)
				(justify mirror)
			)
		)
		(duplicate_pad_numbers_are_jumpers no)
		(fp_line
			(start -1.524 0.762)
			(end 1.524 0.762)
			(stroke
				(width 0.1524)
				(type default)
			)
			(layer "B.SilkS")
		)
		(fp_line
			(start 1.524 0.762)
			(end 1.524 -0.762)
			(stroke
				(width 0.1524)
				(type default)
			)
			(layer "B.SilkS")
		)
		(fp_line
			(start -1.524 -0.762)
			(end -1.524 0.762)
			(stroke
				(width 0.1524)
				(type default)
			)
			(layer "B.SilkS")
		)
		(fp_line
			(start 1.524 -0.762)
			(end -1.524 -0.762)
			(stroke
				(width 0.1524)
				(type default)
			)
			(layer "B.SilkS")
		)
		(fp_line
			(start -1.1049 0.724916)
			(end -1.1049 -0.724916)
			(stroke
				(width 0.1)
				(type default)
			)
			(layer "B.Fab")
		)
		(fp_line
			(start 1.1049 0.724916)
			(end -1.1049 0.724916)
			(stroke
				(width 0.1)
				(type default)
			)
			(layer "B.Fab")
		)
		(fp_line
			(start -1.1049 -0.724916)
			(end 1.1049 -0.724916)
			(stroke
				(width 0.1)
				(type default)
			)
			(layer "B.Fab")
		)
		(fp_line
			(start 1.1049 -0.724916)
			(end 1.1049 0.724916)
			(stroke
				(width 0.1)
				(type default)
			)
			(layer "B.Fab")
		)
		(pad "1" smd rect
			(at 0.889 0 270)
			(size 1.016 1.27)
			(layers "B.Cu" "B.Mask" "B.Paste")
			(net "P12V_S3_AUX_CPU0_NVDIMM")
		)
		(pad "2" smd rect
			(at -0.889 0 270)
			(size 1.016 1.27)
			(layers "B.Cu" "B.Mask" "B.Paste")
			(net "GND")
		)
	)
	(footprint ""
		(layer "B.Cu")
		(at 430.600104 -133.478778)
		(property "Reference" "R2595"
			(at 0 0 0)
			(layer "B.SilkS")
			(hide yes)
			(effects
				(font
					(size 1.27 1.27)
				)
				(justify mirror)
			)
		)
		(property "Value" ""
			(at 0 0 0)
			(layer "B.Fab")
			(effects
				(font
					(size 1.27 1.27)
				)
				(justify mirror)
			)
		)
		(duplicate_pad_numbers_are_jumpers no)
		(fp_line
			(start -0.7874 -0.4064)
			(end -0.7874 0.4064)
			(stroke
				(width 0.1524)
				(type default)
			)
			(layer "B.SilkS")
		)
		(fp_line
			(start -0.7874 0.4064)
			(end 0.7874 0.4064)
			(stroke
				(width 0.1524)
				(type default)
			)
			(layer "B.SilkS")
		)
		(fp_line
			(start 0.7874 -0.4064)
			(end -0.7874 -0.4064)
			(stroke
				(width 0.1524)
				(type default)
			)
			(layer "B.SilkS")
		)
		(fp_line
			(start 0.7874 0.4064)
			(end 0.7874 -0.4064)
			(stroke
				(width 0.1524)
				(type default)
			)
			(layer "B.SilkS")
		)
		(fp_line
			(start -0.67945 -0.3048)
			(end -0.67945 0.3048)
			(stroke
				(width 0.1)
				(type default)
			)
			(layer "B.Fab")
		)
		(fp_line
			(start -0.67945 0.3048)
			(end -0.120396 0.3048)
			(stroke
				(width 0.1)
				(type default)
			)
			(layer "B.Fab")
		)
		(fp_line
			(start -0.12065 -0.3048)
			(end -0.67945 -0.3048)
			(stroke
				(width 0.1)
				(type default)
			)
			(layer "B.Fab")
		)
		(fp_line
			(start -0.12065 -0.2794)
			(end -0.12065 -0.3048)
			(stroke
				(width 0.1)
				(type default)
			)
			(layer "B.Fab")
		)
		(fp_line
			(start -0.120396 0.2794)
			(end 0.12065 0.2794)
			(stroke
				(width 0.1)
				(type default)
			)
			(layer "B.Fab")
		)
		(fp_line
			(start -0.120396 0.3048)
			(end -0.120396 0.2794)
			(stroke
				(width 0.1)
				(type default)
			)
			(layer "B.Fab")
		)
		(fp_line
			(start 0.12065 -0.305054)
			(end 0.12065 -0.2794)
			(stroke
				(width 0.1)
				(type default)
			)
			(layer "B.Fab")
		)
		(fp_line
			(start 0.12065 -0.2794)
			(end -0.12065 -0.2794)
			(stroke
				(width 0.1)
				(type default)
			)
			(layer "B.Fab")
		)
		(fp_line
			(start 0.12065 0.2794)
			(end 0.12065 0.3048)
			(stroke
				(width 0.1)
				(type default)
			)
			(layer "B.Fab")
		)
		(fp_line
			(start 0.12065 0.3048)
			(end 0.67945 0.3048)
			(stroke
				(width 0.1)
				(type default)
			)
			(layer "B.Fab")
		)
		(fp_line
			(start 0.67945 -0.305054)
			(end 0.12065 -0.305054)
			(stroke
				(width 0.1)
				(type default)
			)
			(layer "B.Fab")
		)
		(fp_line
			(start 0.67945 0.3048)
			(end 0.67945 -0.305054)
			(stroke
				(width 0.1)
				(type default)
			)
			(layer "B.Fab")
		)
		(pad "1" smd circle
			(at 0.40005 0 180)
			(size 0 0)
			(layers "B.Cu" "B.Mask" "B.Paste")
			(net "PWRGD_PVCCINFAON_CPU0")
		)
		(pad "2" smd circle
			(at -0.40005 0 180)
			(size 0 0)
			(layers "B.Cu" "B.Mask" "B.Paste")
			(net "PWRGD_PVCCINFAON_CPU0_R")
		)
	)
	(footprint ""
		(layer "B.Cu")
		(at 322.926456 -49.941988 180)
		(property "Reference" "R2971"
			(at 0 0 0)
			(layer "B.SilkS")
			(hide yes)
			(effects
				(font
					(size 1.27 1.27)
				)
				(justify mirror)
			)
		)
		(property "Value" ""
			(at 0 0 0)
			(layer "B.Fab")
			(effects
				(font
					(size 1.27 1.27)
				)
				(justify mirror)
			)
		)
		(duplicate_pad_numbers_are_jumpers no)
		(fp_line
			(start 0.7874 0.4064)
			(end 0.7874 -0.4064)
			(stroke
				(width 0.1524)
				(type default)
			)
			(layer "B.SilkS")
		)
		(fp_line
			(start 0.7874 -0.4064)
			(end -0.7874 -0.4064)
			(stroke
				(width 0.1524)
				(type default)
			)
			(layer "B.SilkS")
		)
		(fp_line
			(start -0.7874 0.4064)
			(end 0.7874 0.4064)
			(stroke
				(width 0.1524)
				(type default)
			)
			(layer "B.SilkS")
		)
		(fp_line
			(start -0.7874 -0.4064)
			(end -0.7874 0.4064)
			(stroke
				(width 0.1524)
				(type default)
			)
			(layer "B.SilkS")
		)
		(fp_line
			(start 0.67945 0.3048)
			(end 0.67945 -0.305054)
			(stroke
				(width 0.1)
				(type default)
			)
			(layer "B.Fab")
		)
		(fp_line
			(start 0.67945 -0.305054)
			(end 0.12065 -0.305054)
			(stroke
				(width 0.1)
				(type default)
			)
			(layer "B.Fab")
		)
		(fp_line
			(start 0.12065 0.3048)
			(end 0.67945 0.3048)
			(stroke
				(width 0.1)
				(type default)
			)
			(layer "B.Fab")
		)
		(fp_line
			(start 0.12065 0.2794)
			(end 0.12065 0.3048)
			(stroke
				(width 0.1)
				(type default)
			)
			(layer "B.Fab")
		)
		(fp_line
			(start 0.12065 -0.2794)
			(end -0.12065 -0.2794)
			(stroke
				(width 0.1)
				(type default)
			)
			(layer "B.Fab")
		)
		(fp_line
			(start 0.12065 -0.305054)
			(end 0.12065 -0.2794)
			(stroke
				(width 0.1)
				(type default)
			)
			(layer "B.Fab")
		)
		(fp_line
			(start -0.120396 0.3048)
			(end -0.120396 0.2794)
			(stroke
				(width 0.1)
				(type default)
			)
			(layer "B.Fab")
		)
		(fp_line
			(start -0.120396 0.2794)
			(end 0.12065 0.2794)
			(stroke
				(width 0.1)
				(type default)
			)
			(layer "B.Fab")
		)
		(fp_line
			(start -0.12065 -0.2794)
			(end -0.12065 -0.3048)
			(stroke
				(width 0.1)
				(type default)
			)
			(layer "B.Fab")
		)
		(fp_line
			(start -0.12065 -0.3048)
			(end -0.67945 -0.3048)
			(stroke
				(width 0.1)
				(type default)
			)
			(layer "B.Fab")
		)
		(fp_line
			(start -0.67945 0.3048)
			(end -0.120396 0.3048)
			(stroke
				(width 0.1)
				(type default)
			)
			(layer "B.Fab")
		)
		(fp_line
			(start -0.67945 -0.3048)
			(end -0.67945 0.3048)
			(stroke
				(width 0.1)
				(type default)
			)
			(layer "B.Fab")
		)
		(pad "1" smd circle
			(at 0.40005 0)
			(size 0 0)
			(layers "B.Cu" "B.Mask" "B.Paste")
			(net "FM_BIOS_DEBUG_EN_N")
		)
		(pad "2" smd circle
			(at -0.40005 0)
			(size 0 0)
			(layers "B.Cu" "B.Mask" "B.Paste")
			(net "FM_BIOS_DEBUG_EN_R_N")
		)
	)
	(footprint ""
		(layer "B.Cu")
		(at 288.746946 -356.036372 -90)
		(property "Reference" "PC623"
			(at 0 0 90)
			(layer "B.SilkS")
			(hide yes)
			(effects
				(font
					(size 1.27 1.27)
				)
				(justify mirror)
			)
		)
		(property "Value" ""
			(at 0 0 90)
			(layer "B.Fab")
			(effects
				(font
					(size 1.27 1.27)
				)
				(justify mirror)
			)
		)
		(duplicate_pad_numbers_are_jumpers no)
		(fp_line
			(start -4.533392 2.249932)
			(end 4.533392 2.249932)
			(stroke
				(width 0.1524)
				(type default)
			)
			(layer "B.SilkS")
		)
		(fp_line
			(start 4.533392 2.249932)
			(end 4.533392 -2.249932)
			(stroke
				(width 0.1524)
				(type default)
			)
			(layer "B.SilkS")
		)
		(fp_line
			(start -4.533392 -2.249932)
			(end -4.533392 2.249932)
			(stroke
				(width 0.1524)
				(type default)
			)
			(layer "B.SilkS")
		)
		(fp_line
			(start 4.533392 -2.249932)
			(end -4.533392 -2.249932)
			(stroke
				(width 0.1524)
				(type default)
			)
			(layer "B.SilkS")
		)
		(fp_poly
			(pts
				(xy 4.533392 -2.326132) (xy 5.39242 -2.326132) (xy 5.39242 2.326132) (xy 4.533392 2.326132)
			)
			(stroke
				(width 0)
				(type default)
			)
			(fill yes)
			(layer "B.SilkS")
		)
		(fp_line
			(start -3.750056 2.249932)
			(end 3.750056 2.249932)
			(stroke
				(width 0.1)
				(type default)
			)
			(layer "B.Fab")
		)
		(fp_line
			(start 3.750056 2.249932)
			(end 3.750056 -2.249932)
			(stroke
				(width 0.1)
				(type default)
			)
			(layer "B.Fab")
		)
		(fp_line
			(start -3.750056 -2.249932)
			(end -3.750056 2.249932)
			(stroke
				(width 0.1)
				(type default)
			)
			(layer "B.Fab")
		)
		(fp_line
			(start 3.750056 -2.249932)
			(end -3.750056 -2.249932)
			(stroke
				(width 0.1)
				(type default)
			)
			(layer "B.Fab")
		)
		(fp_text user "+"
			(at 6.322314 0.786384 180)
			(unlocked yes)
			(layer "B.SilkS")
			(effects
				(font
					(size 1.905 1.4224)
					(thickness 0.1524)
				)
				(justify left mirror)
			)
		)
		(fp_text user "-"
			(at -4.8514 -0.14605 270)
			(unlocked yes)
			(layer "B.SilkS")
			(effects
				(font
					(size 1.905 1.4224)
					(thickness 0.1524)
				)
				(justify left mirror)
			)
		)
		(fp_text user "+"
			(at 6.322314 0.786384 180)
			(unlocked yes)
			(layer "B.Fab")
			(effects
				(font
					(size 1.905 1.4224)
					(thickness 0.1524)
				)
				(justify left mirror)
			)
		)
		(fp_text user "-"
			(at -4.8514 -0.14605 270)
			(unlocked yes)
			(layer "B.Fab")
			(effects
				(font
					(size 1.905 1.4224)
					(thickness 0.1524)
				)
				(justify left mirror)
			)
		)
		(pad "1" smd rect
			(at 3.199892 0 90)
			(size 2.413 2.8194)
			(layers "B.Cu" "B.Mask" "B.Paste")
			(net "PVCCFA_EHV_FIVRA_CPU0")
		)
		(pad "2" smd rect
			(at -3.199892 0 90)
			(size 2.413 2.8194)
			(layers "B.Cu" "B.Mask" "B.Paste")
			(net "GND")
		)
	)
	(footprint ""
		(layer "B.Cu")
		(at 151.69388 -22.824948 -90)
		(property "Reference" "R2212"
			(at 0 0 90)
			(layer "B.SilkS")
			(hide yes)
			(effects
				(font
					(size 1.27 1.27)
				)
				(justify mirror)
			)
		)
		(property "Value" ""
			(at 0 0 90)
			(layer "B.Fab")
			(effects
				(font
					(size 1.27 1.27)
				)
				(justify mirror)
			)
		)
		(duplicate_pad_numbers_are_jumpers no)
		(fp_line
			(start -0.7874 0.4064)
			(end 0.7874 0.4064)
			(stroke
				(width 0.1524)
				(type default)
			)
			(layer "B.SilkS")
		)
		(fp_line
			(start 0.7874 0.4064)
			(end 0.7874 -0.4064)
			(stroke
				(width 0.1524)
				(type default)
			)
			(layer "B.SilkS")
		)
		(fp_line
			(start -0.7874 -0.4064)
			(end -0.7874 0.4064)
			(stroke
				(width 0.1524)
				(type default)
			)
			(layer "B.SilkS")
		)
		(fp_line
			(start 0.7874 -0.4064)
			(end -0.7874 -0.4064)
			(stroke
				(width 0.1524)
				(type default)
			)
			(layer "B.SilkS")
		)
		(fp_line
			(start -0.67945 0.3048)
			(end -0.120396 0.3048)
			(stroke
				(width 0.1)
				(type default)
			)
			(layer "B.Fab")
		)
		(fp_line
			(start -0.120396 0.3048)
			(end -0.120396 0.2794)
			(stroke
				(width 0.1)
				(type default)
			)
			(layer "B.Fab")
		)
		(fp_line
			(start 0.12065 0.3048)
			(end 0.67945 0.3048)
			(stroke
				(width 0.1)
				(type default)
			)
			(layer "B.Fab")
		)
		(fp_line
			(start 0.67945 0.3048)
			(end 0.67945 -0.305054)
			(stroke
				(width 0.1)
				(type default)
			)
			(layer "B.Fab")
		)
		(fp_line
			(start -0.120396 0.2794)
			(end 0.12065 0.2794)
			(stroke
				(width 0.1)
				(type default)
			)
			(layer "B.Fab")
		)
		(fp_line
			(start 0.12065 0.2794)
			(end 0.12065 0.3048)
			(stroke
				(width 0.1)
				(type default)
			)
			(layer "B.Fab")
		)
		(fp_line
			(start -0.12065 -0.2794)
			(end -0.12065 -0.3048)
			(stroke
				(width 0.1)
				(type default)
			)
			(layer "B.Fab")
		)
		(fp_line
			(start 0.12065 -0.2794)
			(end -0.12065 -0.2794)
			(stroke
				(width 0.1)
				(type default)
			)
			(layer "B.Fab")
		)
		(fp_line
			(start -0.67945 -0.3048)
			(end -0.67945 0.3048)
			(stroke
				(width 0.1)
				(type default)
			)
			(layer "B.Fab")
		)
		(fp_line
			(start -0.12065 -0.3048)
			(end -0.67945 -0.3048)
			(stroke
				(width 0.1)
				(type default)
			)
			(layer "B.Fab")
		)
		(fp_line
			(start 0.12065 -0.305054)
			(end 0.12065 -0.2794)
			(stroke
				(width 0.1)
				(type default)
			)
			(layer "B.Fab")
		)
		(fp_line
			(start 0.67945 -0.305054)
			(end 0.12065 -0.305054)
			(stroke
				(width 0.1)
				(type default)
			)
			(layer "B.Fab")
		)
		(pad "1" smd circle
			(at 0.40005 0 90)
			(size 0 0)
			(layers "B.Cu" "B.Mask" "B.Paste")
			(net "SMB_S3M_CPU_3V3AUX_SCL")
		)
		(pad "2" smd circle
			(at -0.40005 0 90)
			(size 0 0)
			(layers "B.Cu" "B.Mask" "B.Paste")
			(net "P3V3_AUX")
		)
	)
)
